(kicad_pcb
	(version 20260206)
	(generator "pcbnew")
	(generator_version "10.0")
	(general
		(thickness 1.6)
		(legacy_teardrops no)
	)
	(paper "A4")
	(title_block
		(title "9054_F0T_PDB_BD_GPU_F_V04_1213_1550_OCP.brd")
		(comment 1 "Grand Teton / footprints 482-488 of 608")
	)
	(layers
		(0 "F.Cu" signal "TOP")
		(4 "In1.Cu" signal "GND")
		(6 "In2.Cu" signal "IN1")
		(8 "In3.Cu" signal "GND1")
		(10 "In4.Cu" signal "VCC")
		(12 "In5.Cu" signal "VCC1")
		(14 "In6.Cu" signal "GND2")
		(16 "In7.Cu" signal "IN2")
		(18 "In8.Cu" signal "GND3")
		(2 "B.Cu" signal "BOTTOM")
		(9 "F.Adhes" user "F.Adhesive")
		(11 "B.Adhes" user "B.Adhesive")
		(13 "F.Paste" user "Package Geometry/Pastemask Top")
		(15 "B.Paste" user "Package Geometry/Pastemask Bottom")
		(5 "F.SilkS" user "Ref Des/Silkscreen Top")
		(7 "B.SilkS" user "Ref Des/Silkscreen Bottom")
		(1 "F.Mask" user "Board Geometry/Soldermask Top")
		(3 "B.Mask" user "Board Geometry/Soldermask Bottom")
		(17 "Dwgs.User" user "User.Drawings")
		(19 "Cmts.User" user "User.Comments")
		(21 "Eco1.User" user "User.Eco1")
		(23 "Eco2.User" user "User.Eco2")
		(25 "Edge.Cuts" user "Board Geometry/Outline")
		(27 "Margin" user)
		(31 "F.CrtYd" user "Package Geometry/Place Bound Top")
		(29 "B.CrtYd" user "Package Geometry/Place Bound Bottom")
		(35 "F.Fab" user "Ref Des/Assembly Top")
		(33 "B.Fab" user "Ref Des/Assembly Bottom")
	)
	(footprint ""
		(layer "B.Cu")
		(at 284.8864 -69.723)
		(property "Reference" "PR28"
			(at 0 0 0)
			(layer "B.SilkS")
			(hide yes)
			(effects
				(font
					(size 1.27 1.27)
				)
				(justify mirror)
			)
		)
		(property "Value" ""
			(at 0 0 0)
			(layer "B.Fab")
			(effects
				(font
					(size 1.27 1.27)
				)
				(justify mirror)
			)
		)
		(duplicate_pad_numbers_are_jumpers no)
		(fp_line
			(start -0.7874 -0.4064)
			(end -0.7874 0.4064)
			(stroke
				(width 0.1524)
				(type default)
			)
			(layer "B.SilkS")
		)
		(fp_line
			(start -0.7874 0.4064)
			(end 0.7874 0.4064)
			(stroke
				(width 0.1524)
				(type default)
			)
			(layer "B.SilkS")
		)
		(fp_line
			(start 0.7874 -0.4064)
			(end -0.7874 -0.4064)
			(stroke
				(width 0.1524)
				(type default)
			)
			(layer "B.SilkS")
		)
		(fp_line
			(start 0.7874 0.4064)
			(end 0.7874 -0.4064)
			(stroke
				(width 0.1524)
				(type default)
			)
			(layer "B.SilkS")
		)
		(fp_line
			(start -0.67945 -0.3048)
			(end -0.67945 0.3048)
			(stroke
				(width 0.1)
				(type default)
			)
			(layer "B.Fab")
		)
		(fp_line
			(start -0.67945 0.3048)
			(end -0.120396 0.3048)
			(stroke
				(width 0.1)
				(type default)
			)
			(layer "B.Fab")
		)
		(fp_line
			(start -0.12065 -0.3048)
			(end -0.67945 -0.3048)
			(stroke
				(width 0.1)
				(type default)
			)
			(layer "B.Fab")
		)
		(fp_line
			(start -0.12065 -0.2794)
			(end -0.12065 -0.3048)
			(stroke
				(width 0.1)
				(type default)
			)
			(layer "B.Fab")
		)
		(fp_line
			(start -0.120396 0.2794)
			(end 0.12065 0.2794)
			(stroke
				(width 0.1)
				(type default)
			)
			(layer "B.Fab")
		)
		(fp_line
			(start -0.120396 0.3048)
			(end -0.120396 0.2794)
			(stroke
				(width 0.1)
				(type default)
			)
			(layer "B.Fab")
		)
		(fp_line
			(start 0.12065 -0.305054)
			(end 0.12065 -0.2794)
			(stroke
				(width 0.1)
				(type default)
			)
			(layer "B.Fab")
		)
		(fp_line
			(start 0.12065 -0.2794)
			(end -0.12065 -0.2794)
			(stroke
				(width 0.1)
				(type default)
			)
			(layer "B.Fab")
		)
		(fp_line
			(start 0.12065 0.2794)
			(end 0.12065 0.3048)
			(stroke
				(width 0.1)
				(type default)
			)
			(layer "B.Fab")
		)
		(fp_line
			(start 0.12065 0.3048)
			(end 0.67945 0.3048)
			(stroke
				(width 0.1)
				(type default)
			)
			(layer "B.Fab")
		)
		(fp_line
			(start 0.67945 -0.305054)
			(end 0.12065 -0.305054)
			(stroke
				(width 0.1)
				(type default)
			)
			(layer "B.Fab")
		)
		(fp_line
			(start 0.67945 0.3048)
			(end 0.67945 -0.305054)
			(stroke
				(width 0.1)
				(type default)
			)
			(layer "B.Fab")
		)
		(pad "1" smd circle
			(at 0.40005 0 180)
			(size 0 0)
			(layers "B.Cu" "B.Mask" "B.Paste")
			(net "P52V_HS1_SCK")
		)
		(pad "2" smd circle
			(at -0.40005 0 180)
			(size 0 0)
			(layers "B.Cu" "B.Mask" "B.Paste")
			(net "GND_FIELD_SIGNAL")
		)
	)
	(footprint ""
		(layer "B.Cu")
		(at 169.77868 -151.939498 -90)
		(property "Reference" "J13"
			(at 3.5052 -5.552948 270)
			(unlocked yes)
			(layer "B.SilkS")
			(effects
				(font
					(size 0.7874 0.5842)
					(thickness 0.1524)
				)
				(justify left mirror)
			)
		)
		(property "Value" ""
			(at 0 0 90)
			(layer "B.Fab")
			(effects
				(font
					(size 1.27 1.27)
				)
				(justify mirror)
			)
		)
		(duplicate_pad_numbers_are_jumpers no)
		(fp_line
			(start 0 4.011168)
			(end 3.330702 -4.771136)
			(stroke
				(width 0.1524)
				(type default)
			)
			(layer "B.SilkS")
		)
		(fp_line
			(start -3.330702 -4.771136)
			(end 0 4.011168)
			(stroke
				(width 0.1524)
				(type default)
			)
			(layer "B.SilkS")
		)
		(fp_line
			(start 3.330702 -4.771136)
			(end -3.330702 -4.771136)
			(stroke
				(width 0.1524)
				(type default)
			)
			(layer "B.SilkS")
		)
		(fp_line
			(start 0 4.011168)
			(end 3.330702 -4.771136)
			(stroke
				(width 0.1)
				(type default)
			)
			(layer "B.Fab")
		)
		(fp_line
			(start -3.330702 -4.771136)
			(end 0 4.011168)
			(stroke
				(width 0.1)
				(type default)
			)
			(layer "B.Fab")
		)
		(fp_line
			(start 3.330702 -4.771136)
			(end -3.330702 -4.771136)
			(stroke
				(width 0.1)
				(type default)
			)
			(layer "B.Fab")
		)
		(pad "1" thru_hole circle
			(at 0 0 90)
			(size 2.159 2.159)
			(drill 1.7018)
			(layers "*.Cu" "*.Mask")
			(remove_unused_layers no)
			(net "GND3")
			(clearance 0.0254)
			(thermal_gap 0.0254)
		)
		(pad "2" thru_hole circle
			(at 1.27 -3.348736 90)
			(size 2.159 2.159)
			(drill 1.7018)
			(layers "*.Cu" "*.Mask")
			(remove_unused_layers no)
			(net "TDR_SE_50_OHM_IN2")
			(clearance 0.0254)
			(thermal_gap 0.0254)
		)
		(pad "3" thru_hole circle
			(at -1.27 -3.348736 90)
			(size 2.159 2.159)
			(drill 1.7018)
			(layers "*.Cu" "*.Mask")
			(remove_unused_layers no)
			(net "TDR_SE_50_OHM_IN2")
			(clearance 0.0254)
			(thermal_gap 0.0254)
		)
	)
	(footprint ""
		(layer "B.Cu")
		(at 426.593 -38.989)
		(property "Reference" "R5936"
			(at 0 0 0)
			(layer "B.SilkS")
			(hide yes)
			(effects
				(font
					(size 1.27 1.27)
				)
				(justify mirror)
			)
		)
		(property "Value" ""
			(at 0 0 0)
			(layer "B.Fab")
			(effects
				(font
					(size 1.27 1.27)
				)
				(justify mirror)
			)
		)
		(duplicate_pad_numbers_are_jumpers no)
		(fp_line
			(start -0.7874 -0.4064)
			(end -0.7874 0.4064)
			(stroke
				(width 0.1524)
				(type default)
			)
			(layer "B.SilkS")
		)
		(fp_line
			(start -0.7874 0.4064)
			(end 0.7874 0.4064)
			(stroke
				(width 0.1524)
				(type default)
			)
			(layer "B.SilkS")
		)
		(fp_line
			(start 0.7874 -0.4064)
			(end -0.7874 -0.4064)
			(stroke
				(width 0.1524)
				(type default)
			)
			(layer "B.SilkS")
		)
		(fp_line
			(start 0.7874 0.4064)
			(end 0.7874 -0.4064)
			(stroke
				(width 0.1524)
				(type default)
			)
			(layer "B.SilkS")
		)
		(fp_line
			(start -0.67945 -0.3048)
			(end -0.67945 0.3048)
			(stroke
				(width 0.1)
				(type default)
			)
			(layer "B.Fab")
		)
		(fp_line
			(start -0.67945 0.3048)
			(end -0.120396 0.3048)
			(stroke
				(width 0.1)
				(type default)
			)
			(layer "B.Fab")
		)
		(fp_line
			(start -0.12065 -0.3048)
			(end -0.67945 -0.3048)
			(stroke
				(width 0.1)
				(type default)
			)
			(layer "B.Fab")
		)
		(fp_line
			(start -0.12065 -0.2794)
			(end -0.12065 -0.3048)
			(stroke
				(width 0.1)
				(type default)
			)
			(layer "B.Fab")
		)
		(fp_line
			(start -0.120396 0.2794)
			(end 0.12065 0.2794)
			(stroke
				(width 0.1)
				(type default)
			)
			(layer "B.Fab")
		)
		(fp_line
			(start -0.120396 0.3048)
			(end -0.120396 0.2794)
			(stroke
				(width 0.1)
				(type default)
			)
			(layer "B.Fab")
		)
		(fp_line
			(start 0.12065 -0.305054)
			(end 0.12065 -0.2794)
			(stroke
				(width 0.1)
				(type default)
			)
			(layer "B.Fab")
		)
		(fp_line
			(start 0.12065 -0.2794)
			(end -0.12065 -0.2794)
			(stroke
				(width 0.1)
				(type default)
			)
			(layer "B.Fab")
		)
		(fp_line
			(start 0.12065 0.2794)
			(end 0.12065 0.3048)
			(stroke
				(width 0.1)
				(type default)
			)
			(layer "B.Fab")
		)
		(fp_line
			(start 0.12065 0.3048)
			(end 0.67945 0.3048)
			(stroke
				(width 0.1)
				(type default)
			)
			(layer "B.Fab")
		)
		(fp_line
			(start 0.67945 -0.305054)
			(end 0.12065 -0.305054)
			(stroke
				(width 0.1)
				(type default)
			)
			(layer "B.Fab")
		)
		(fp_line
			(start 0.67945 0.3048)
			(end 0.67945 -0.305054)
			(stroke
				(width 0.1)
				(type default)
			)
			(layer "B.Fab")
		)
		(pad "1" smd circle
			(at 0.40005 0 180)
			(size 0 0)
			(layers "B.Cu" "B.Mask" "B.Paste")
			(net "P3V3_AUX")
		)
		(pad "2" smd circle
			(at -0.40005 0 180)
			(size 0 0)
			(layers "B.Cu" "B.Mask" "B.Paste")
			(net "PCA9555_2_A0")
		)
	)
	(footprint ""
		(layer "B.Cu")
		(at 282.702 -88.773 -90)
		(property "Reference" "R5901"
			(at 0 0 90)
			(layer "B.SilkS")
			(hide yes)
			(effects
				(font
					(size 1.27 1.27)
				)
				(justify mirror)
			)
		)
		(property "Value" ""
			(at 0 0 90)
			(layer "B.Fab")
			(effects
				(font
					(size 1.27 1.27)
				)
				(justify mirror)
			)
		)
		(duplicate_pad_numbers_are_jumpers no)
		(fp_line
			(start -1.651 0.8382)
			(end 1.651 0.8382)
			(stroke
				(width 0.1524)
				(type default)
			)
			(layer "B.SilkS")
		)
		(fp_line
			(start 1.651 0.8382)
			(end 1.651 -0.8382)
			(stroke
				(width 0.1524)
				(type default)
			)
			(layer "B.SilkS")
		)
		(fp_line
			(start -1.651 -0.8382)
			(end -1.651 0.8382)
			(stroke
				(width 0.1524)
				(type default)
			)
			(layer "B.SilkS")
		)
		(fp_line
			(start 1.651 -0.8382)
			(end -1.651 -0.8382)
			(stroke
				(width 0.1524)
				(type default)
			)
			(layer "B.SilkS")
		)
		(fp_line
			(start -1.560576 0.7366)
			(end -1.560576 -0.7366)
			(stroke
				(width 0.1)
				(type default)
			)
			(layer "B.Fab")
		)
		(fp_line
			(start -1.524 0.7366)
			(end -1.560576 0.7366)
			(stroke
				(width 0.1)
				(type default)
			)
			(layer "B.Fab")
		)
		(fp_line
			(start 1.524 0.7366)
			(end -1.524 0.7366)
			(stroke
				(width 0.1)
				(type default)
			)
			(layer "B.Fab")
		)
		(fp_line
			(start 1.559814 0.7366)
			(end 1.524 0.7366)
			(stroke
				(width 0.1)
				(type default)
			)
			(layer "B.Fab")
		)
		(fp_line
			(start -1.560576 -0.7366)
			(end -1.524 -0.7366)
			(stroke
				(width 0.1)
				(type default)
			)
			(layer "B.Fab")
		)
		(fp_line
			(start -1.524 -0.7366)
			(end 1.524 -0.7366)
			(stroke
				(width 0.1)
				(type default)
			)
			(layer "B.Fab")
		)
		(fp_line
			(start 1.524 -0.7366)
			(end 1.559814 -0.7366)
			(stroke
				(width 0.1)
				(type default)
			)
			(layer "B.Fab")
		)
		(fp_line
			(start 1.559814 -0.7366)
			(end 1.559814 0.7366)
			(stroke
				(width 0.1)
				(type default)
			)
			(layer "B.Fab")
		)
		(pad "1" smd rect
			(at 0.94996 0 270)
			(size 1.1176 1.3716)
			(layers "B.Cu" "B.Mask" "B.Paste")
			(net "P52V_1")
		)
		(pad "2" smd rect
			(at -0.94996 0 270)
			(size 1.1176 1.3716)
			(layers "B.Cu" "B.Mask" "B.Paste")
			(net "P3V3_AND")
		)
	)
	(footprint ""
		(layer "B.Cu")
		(at 272.8214 -76.454 -90)
		(property "Reference" "PR6931"
			(at 0 0 90)
			(layer "B.SilkS")
			(hide yes)
			(effects
				(font
					(size 1.27 1.27)
				)
				(justify mirror)
			)
		)
		(property "Value" ""
			(at 0 0 90)
			(layer "B.Fab")
			(effects
				(font
					(size 1.27 1.27)
				)
				(justify mirror)
			)
		)
		(duplicate_pad_numbers_are_jumpers no)
		(fp_line
			(start -0.7874 0.4064)
			(end 0.7874 0.4064)
			(stroke
				(width 0.1524)
				(type default)
			)
			(layer "B.SilkS")
		)
		(fp_line
			(start 0.7874 0.4064)
			(end 0.7874 -0.4064)
			(stroke
				(width 0.1524)
				(type default)
			)
			(layer "B.SilkS")
		)
		(fp_line
			(start -0.7874 -0.4064)
			(end -0.7874 0.4064)
			(stroke
				(width 0.1524)
				(type default)
			)
			(layer "B.SilkS")
		)
		(fp_line
			(start 0.7874 -0.4064)
			(end -0.7874 -0.4064)
			(stroke
				(width 0.1524)
				(type default)
			)
			(layer "B.SilkS")
		)
		(fp_line
			(start -0.67945 0.3048)
			(end -0.120396 0.3048)
			(stroke
				(width 0.1)
				(type default)
			)
			(layer "B.Fab")
		)
		(fp_line
			(start -0.120396 0.3048)
			(end -0.120396 0.2794)
			(stroke
				(width 0.1)
				(type default)
			)
			(layer "B.Fab")
		)
		(fp_line
			(start 0.12065 0.3048)
			(end 0.67945 0.3048)
			(stroke
				(width 0.1)
				(type default)
			)
			(layer "B.Fab")
		)
		(fp_line
			(start 0.67945 0.3048)
			(end 0.67945 -0.305054)
			(stroke
				(width 0.1)
				(type default)
			)
			(layer "B.Fab")
		)
		(fp_line
			(start -0.120396 0.2794)
			(end 0.12065 0.2794)
			(stroke
				(width 0.1)
				(type default)
			)
			(layer "B.Fab")
		)
		(fp_line
			(start 0.12065 0.2794)
			(end 0.12065 0.3048)
			(stroke
				(width 0.1)
				(type default)
			)
			(layer "B.Fab")
		)
		(fp_line
			(start -0.12065 -0.2794)
			(end -0.12065 -0.3048)
			(stroke
				(width 0.1)
				(type default)
			)
			(layer "B.Fab")
		)
		(fp_line
			(start 0.12065 -0.2794)
			(end -0.12065 -0.2794)
			(stroke
				(width 0.1)
				(type default)
			)
			(layer "B.Fab")
		)
		(fp_line
			(start -0.67945 -0.3048)
			(end -0.67945 0.3048)
			(stroke
				(width 0.1)
				(type default)
			)
			(layer "B.Fab")
		)
		(fp_line
			(start -0.12065 -0.3048)
			(end -0.67945 -0.3048)
			(stroke
				(width 0.1)
				(type default)
			)
			(layer "B.Fab")
		)
		(fp_line
			(start 0.12065 -0.305054)
			(end 0.12065 -0.2794)
			(stroke
				(width 0.1)
				(type default)
			)
			(layer "B.Fab")
		)
		(fp_line
			(start 0.67945 -0.305054)
			(end 0.12065 -0.305054)
			(stroke
				(width 0.1)
				(type default)
			)
			(layer "B.Fab")
		)
		(pad "1" smd circle
			(at 0.40005 0 90)
			(size 0 0)
			(layers "B.Cu" "B.Mask" "B.Paste")
			(net "P52V_HS1_UVH")
		)
		(pad "2" smd circle
			(at -0.40005 0 90)
			(size 0 0)
			(layers "B.Cu" "B.Mask" "B.Paste")
			(net "GND_FIELD_SIGNAL")
		)
	)
	(footprint ""
		(layer "B.Cu")
		(at 298.704 -90.17 -90)
		(property "Reference" "R5943"
			(at 0 0 90)
			(layer "B.SilkS")
			(hide yes)
			(effects
				(font
					(size 1.27 1.27)
				)
				(justify mirror)
			)
		)
		(property "Value" ""
			(at 0 0 90)
			(layer "B.Fab")
			(effects
				(font
					(size 1.27 1.27)
				)
				(justify mirror)
			)
		)
		(duplicate_pad_numbers_are_jumpers no)
		(fp_line
			(start -0.7874 0.4064)
			(end 0.7874 0.4064)
			(stroke
				(width 0.1524)
				(type default)
			)
			(layer "B.SilkS")
		)
		(fp_line
			(start 0.7874 0.4064)
			(end 0.7874 -0.4064)
			(stroke
				(width 0.1524)
				(type default)
			)
			(layer "B.SilkS")
		)
		(fp_line
			(start -0.7874 -0.4064)
			(end -0.7874 0.4064)
			(stroke
				(width 0.1524)
				(type default)
			)
			(layer "B.SilkS")
		)
		(fp_line
			(start 0.7874 -0.4064)
			(end -0.7874 -0.4064)
			(stroke
				(width 0.1524)
				(type default)
			)
			(layer "B.SilkS")
		)
		(fp_line
			(start -0.67945 0.3048)
			(end -0.120396 0.3048)
			(stroke
				(width 0.1)
				(type default)
			)
			(layer "B.Fab")
		)
		(fp_line
			(start -0.120396 0.3048)
			(end -0.120396 0.2794)
			(stroke
				(width 0.1)
				(type default)
			)
			(layer "B.Fab")
		)
		(fp_line
			(start 0.12065 0.3048)
			(end 0.67945 0.3048)
			(stroke
				(width 0.1)
				(type default)
			)
			(layer "B.Fab")
		)
		(fp_line
			(start 0.67945 0.3048)
			(end 0.67945 -0.305054)
			(stroke
				(width 0.1)
				(type default)
			)
			(layer "B.Fab")
		)
		(fp_line
			(start -0.120396 0.2794)
			(end 0.12065 0.2794)
			(stroke
				(width 0.1)
				(type default)
			)
			(layer "B.Fab")
		)
		(fp_line
			(start 0.12065 0.2794)
			(end 0.12065 0.3048)
			(stroke
				(width 0.1)
				(type default)
			)
			(layer "B.Fab")
		)
		(fp_line
			(start -0.12065 -0.2794)
			(end -0.12065 -0.3048)
			(stroke
				(width 0.1)
				(type default)
			)
			(layer "B.Fab")
		)
		(fp_line
			(start 0.12065 -0.2794)
			(end -0.12065 -0.2794)
			(stroke
				(width 0.1)
				(type default)
			)
			(layer "B.Fab")
		)
		(fp_line
			(start -0.67945 -0.3048)
			(end -0.67945 0.3048)
			(stroke
				(width 0.1)
				(type default)
			)
			(layer "B.Fab")
		)
		(fp_line
			(start -0.12065 -0.3048)
			(end -0.67945 -0.3048)
			(stroke
				(width 0.1)
				(type default)
			)
			(layer "B.Fab")
		)
		(fp_line
			(start 0.12065 -0.305054)
			(end 0.12065 -0.2794)
			(stroke
				(width 0.1)
				(type default)
			)
			(layer "B.Fab")
		)
		(fp_line
			(start 0.67945 -0.305054)
			(end 0.12065 -0.305054)
			(stroke
				(width 0.1)
				(type default)
			)
			(layer "B.Fab")
		)
		(pad "1" smd circle
			(at 0.40005 0 90)
			(size 0 0)
			(layers "B.Cu" "B.Mask" "B.Paste")
			(net "P3V3_AUX")
		)
		(pad "2" smd circle
			(at -0.40005 0 90)
			(size 0 0)
			(layers "B.Cu" "B.Mask" "B.Paste")
			(net "FM_HS1_EN_FUSE_BUF")
		)
	)
	(footprint ""
		(layer "B.Cu")
		(at 183.942736 -77.47)
		(property "Reference" "PR7033"
			(at 0 0 0)
			(layer "B.SilkS")
			(hide yes)
			(effects
				(font
					(size 1.27 1.27)
				)
				(justify mirror)
			)
		)
		(property "Value" ""
			(at 0 0 0)
			(layer "B.Fab")
			(effects
				(font
					(size 1.27 1.27)
				)
				(justify mirror)
			)
		)
		(duplicate_pad_numbers_are_jumpers no)
		(fp_line
			(start -1.651 -0.8382)
			(end -1.651 0.8382)
			(stroke
				(width 0.1524)
				(type default)
			)
			(layer "B.SilkS")
		)
		(fp_line
			(start -1.651 0.8382)
			(end 1.651 0.8382)
			(stroke
				(width 0.1524)
				(type default)
			)
			(layer "B.SilkS")
		)
		(fp_line
			(start 1.651 -0.8382)
			(end -1.651 -0.8382)
			(stroke
				(width 0.1524)
				(type default)
			)
			(layer "B.SilkS")
		)
		(fp_line
			(start 1.651 0.8382)
			(end 1.651 -0.8382)
			(stroke
				(width 0.1524)
				(type default)
			)
			(layer "B.SilkS")
		)
		(fp_line
			(start -1.560576 -0.7366)
			(end -1.524 -0.7366)
			(stroke
				(width 0.1)
				(type default)
			)
			(layer "B.Fab")
		)
		(fp_line
			(start -1.560576 0.7366)
			(end -1.560576 -0.7366)
			(stroke
				(width 0.1)
				(type default)
			)
			(layer "B.Fab")
		)
		(fp_line
			(start -1.524 -0.7366)
			(end 1.524 -0.7366)
			(stroke
				(width 0.1)
				(type default)
			)
			(layer "B.Fab")
		)
		(fp_line
			(start -1.524 0.7366)
			(end -1.560576 0.7366)
			(stroke
				(width 0.1)
				(type default)
			)
			(layer "B.Fab")
		)
		(fp_line
			(start 1.524 -0.7366)
			(end 1.559814 -0.7366)
			(stroke
				(width 0.1)
				(type default)
			)
			(layer "B.Fab")
		)
		(fp_line
			(start 1.524 0.7366)
			(end -1.524 0.7366)
			(stroke
				(width 0.1)
				(type default)
			)
			(layer "B.Fab")
		)
		(fp_line
			(start 1.559814 -0.7366)
			(end 1.559814 0.7366)
			(stroke
				(width 0.1)
				(type default)
			)
			(layer "B.Fab")
		)
		(fp_line
			(start 1.559814 0.7366)
			(end 1.524 0.7366)
			(stroke
				(width 0.1)
				(type default)
			)
			(layer "B.Fab")
		)
		(pad "1" smd rect
			(at 0.94996 0)
			(size 1.1176 1.3716)
			(layers "B.Cu" "B.Mask" "B.Paste")
			(net "P52V_HS2_DV_DT_R")
		)
		(pad "2" smd rect
			(at -0.94996 0)
			(size 1.1176 1.3716)
			(layers "B.Cu" "B.Mask" "B.Paste")
			(net "P52V_HS2_DV_DT")
		)
	)
)
